(kicad_pcb
	(version 20260206)
	(generator "pcbnew")
	(generator_version "10.0")
	(general
		(thickness 1.6)
		(legacy_teardrops no)
	)
	(paper "A4")
	(title_block
		(title "04192023_DAF0TMB3IC0_F0TG_MB_C_brd_V02_OCP.brd")
		(comment 1 "Grand Teton / footprints 4768-4774 of 8354")
	)
	(layers
		(0 "F.Cu" signal "TOP")
		(4 "In1.Cu" signal "GND")
		(6 "In2.Cu" signal "IN1")
		(8 "In3.Cu" signal "GND1")
		(10 "In4.Cu" signal "IN2")
		(12 "In5.Cu" signal "GND2")
		(14 "In6.Cu" signal "IN3")
		(16 "In7.Cu" signal "GND3")
		(18 "In8.Cu" signal "VCC")
		(20 "In9.Cu" signal "VCC1")
		(22 "In10.Cu" signal "GND4")
		(24 "In11.Cu" signal "IN4")
		(26 "In12.Cu" signal "GND5")
		(28 "In13.Cu" signal "IN5")
		(30 "In14.Cu" signal "GND6")
		(32 "In15.Cu" signal "IN6")
		(34 "In16.Cu" signal "GND7")
		(2 "B.Cu" signal "BOTTOM")
		(9 "F.Adhes" user "F.Adhesive")
		(11 "B.Adhes" user "B.Adhesive")
		(13 "F.Paste" user "Package Geometry/Pastemask Top")
		(15 "B.Paste" user "Package Geometry/Pastemask Bottom")
		(5 "F.SilkS" user "Ref Des/Silkscreen Top")
		(7 "B.SilkS" user "Ref Des/Silkscreen Bottom")
		(1 "F.Mask" user "Board Geometry/Soldermask Top")
		(3 "B.Mask" user "Board Geometry/Soldermask Bottom")
		(17 "Dwgs.User" user "User.Drawings")
		(19 "Cmts.User" user "User.Comments")
		(21 "Eco1.User" user "User.Eco1")
		(23 "Eco2.User" user "User.Eco2")
		(25 "Edge.Cuts" user "Board Geometry/Outline")
		(27 "Margin" user)
		(31 "F.CrtYd" user "Package Geometry/Place Bound Top")
		(29 "B.CrtYd" user "Package Geometry/Place Bound Bottom")
		(35 "F.Fab" user "Ref Des/Assembly Top")
		(33 "B.Fab" user "Ref Des/Assembly Bottom")
	)
	(footprint ""
		(layer "F.Cu")
		(at 185.027316 -428.372016 90)
		(property "Reference" "R3443"
			(at 0 0 90)
			(layer "F.SilkS")
			(hide yes)
			(effects
				(font
					(size 1.27 1.27)
				)
			)
		)
		(property "Value" ""
			(at 0 0 90)
			(layer "F.Fab")
			(effects
				(font
					(size 1.27 1.27)
				)
			)
		)
		(duplicate_pad_numbers_are_jumpers no)
		(fp_line
			(start 0.7874 -0.4064)
			(end 0.7874 0.4064)
			(stroke
				(width 0.1524)
				(type default)
			)
			(layer "F.SilkS")
		)
		(fp_line
			(start -0.7874 -0.4064)
			(end 0.7874 -0.4064)
			(stroke
				(width 0.1524)
				(type default)
			)
			(layer "F.SilkS")
		)
		(fp_line
			(start 0.7874 0.4064)
			(end -0.7874 0.4064)
			(stroke
				(width 0.1524)
				(type default)
			)
			(layer "F.SilkS")
		)
		(fp_line
			(start -0.7874 0.4064)
			(end -0.7874 -0.4064)
			(stroke
				(width 0.1524)
				(type default)
			)
			(layer "F.SilkS")
		)
		(fp_line
			(start -0.12065 -0.305054)
			(end -0.12065 -0.2794)
			(stroke
				(width 0.1)
				(type default)
			)
			(layer "F.Fab")
		)
		(fp_line
			(start -0.67945 -0.305054)
			(end -0.12065 -0.305054)
			(stroke
				(width 0.1)
				(type default)
			)
			(layer "F.Fab")
		)
		(fp_line
			(start 0.67945 -0.3048)
			(end 0.67945 0.3048)
			(stroke
				(width 0.1)
				(type default)
			)
			(layer "F.Fab")
		)
		(fp_line
			(start 0.12065 -0.3048)
			(end 0.67945 -0.3048)
			(stroke
				(width 0.1)
				(type default)
			)
			(layer "F.Fab")
		)
		(fp_line
			(start 0.12065 -0.2794)
			(end 0.12065 -0.3048)
			(stroke
				(width 0.1)
				(type default)
			)
			(layer "F.Fab")
		)
		(fp_line
			(start -0.12065 -0.2794)
			(end 0.12065 -0.2794)
			(stroke
				(width 0.1)
				(type default)
			)
			(layer "F.Fab")
		)
		(fp_line
			(start 0.120396 0.2794)
			(end -0.12065 0.2794)
			(stroke
				(width 0.1)
				(type default)
			)
			(layer "F.Fab")
		)
		(fp_line
			(start -0.12065 0.2794)
			(end -0.12065 0.3048)
			(stroke
				(width 0.1)
				(type default)
			)
			(layer "F.Fab")
		)
		(fp_line
			(start 0.67945 0.3048)
			(end 0.120396 0.3048)
			(stroke
				(width 0.1)
				(type default)
			)
			(layer "F.Fab")
		)
		(fp_line
			(start 0.120396 0.3048)
			(end 0.120396 0.2794)
			(stroke
				(width 0.1)
				(type default)
			)
			(layer "F.Fab")
		)
		(fp_line
			(start -0.12065 0.3048)
			(end -0.67945 0.3048)
			(stroke
				(width 0.1)
				(type default)
			)
			(layer "F.Fab")
		)
		(fp_line
			(start -0.67945 0.3048)
			(end -0.67945 -0.305054)
			(stroke
				(width 0.1)
				(type default)
			)
			(layer "F.Fab")
		)
		(pad "1" smd circle
			(at -0.40005 0 90)
			(size 0 0)
			(layers "F.Cu" "F.Mask" "F.Paste")
			(net "GPU_PEX_STRAP1")
		)
		(pad "2" smd circle
			(at 0.40005 0 90)
			(size 0 0)
			(layers "F.Cu" "F.Mask" "F.Paste")
			(net "GND")
		)
	)
	(footprint ""
		(layer "F.Cu")
		(at 188.28258 -29.758386 -90)
		(property "Reference" "PR4003"
			(at 0 0 270)
			(layer "F.SilkS")
			(hide yes)
			(effects
				(font
					(size 1.27 1.27)
				)
			)
		)
		(property "Value" ""
			(at 0 0 270)
			(layer "F.Fab")
			(effects
				(font
					(size 1.27 1.27)
				)
			)
		)
		(duplicate_pad_numbers_are_jumpers no)
		(fp_line
			(start -0.7874 0.4064)
			(end -0.7874 -0.4064)
			(stroke
				(width 0.1524)
				(type default)
			)
			(layer "F.SilkS")
		)
		(fp_line
			(start 0.7874 0.4064)
			(end -0.7874 0.4064)
			(stroke
				(width 0.1524)
				(type default)
			)
			(layer "F.SilkS")
		)
		(fp_line
			(start -0.7874 -0.4064)
			(end 0.7874 -0.4064)
			(stroke
				(width 0.1524)
				(type default)
			)
			(layer "F.SilkS")
		)
		(fp_line
			(start 0.7874 -0.4064)
			(end 0.7874 0.4064)
			(stroke
				(width 0.1524)
				(type default)
			)
			(layer "F.SilkS")
		)
		(fp_line
			(start -0.67945 0.3048)
			(end -0.67945 -0.305054)
			(stroke
				(width 0.1)
				(type default)
			)
			(layer "F.Fab")
		)
		(fp_line
			(start -0.12065 0.3048)
			(end -0.67945 0.3048)
			(stroke
				(width 0.1)
				(type default)
			)
			(layer "F.Fab")
		)
		(fp_line
			(start 0.120396 0.3048)
			(end 0.120396 0.2794)
			(stroke
				(width 0.1)
				(type default)
			)
			(layer "F.Fab")
		)
		(fp_line
			(start 0.67945 0.3048)
			(end 0.120396 0.3048)
			(stroke
				(width 0.1)
				(type default)
			)
			(layer "F.Fab")
		)
		(fp_line
			(start -0.12065 0.2794)
			(end -0.12065 0.3048)
			(stroke
				(width 0.1)
				(type default)
			)
			(layer "F.Fab")
		)
		(fp_line
			(start 0.120396 0.2794)
			(end -0.12065 0.2794)
			(stroke
				(width 0.1)
				(type default)
			)
			(layer "F.Fab")
		)
		(fp_line
			(start -0.12065 -0.2794)
			(end 0.12065 -0.2794)
			(stroke
				(width 0.1)
				(type default)
			)
			(layer "F.Fab")
		)
		(fp_line
			(start 0.12065 -0.2794)
			(end 0.12065 -0.3048)
			(stroke
				(width 0.1)
				(type default)
			)
			(layer "F.Fab")
		)
		(fp_line
			(start 0.12065 -0.3048)
			(end 0.67945 -0.3048)
			(stroke
				(width 0.1)
				(type default)
			)
			(layer "F.Fab")
		)
		(fp_line
			(start 0.67945 -0.3048)
			(end 0.67945 0.3048)
			(stroke
				(width 0.1)
				(type default)
			)
			(layer "F.Fab")
		)
		(fp_line
			(start -0.67945 -0.305054)
			(end -0.12065 -0.305054)
			(stroke
				(width 0.1)
				(type default)
			)
			(layer "F.Fab")
		)
		(fp_line
			(start -0.12065 -0.305054)
			(end -0.12065 -0.2794)
			(stroke
				(width 0.1)
				(type default)
			)
			(layer "F.Fab")
		)
		(pad "1" smd circle
			(at -0.40005 0 270)
			(size 0 0)
			(layers "F.Cu" "F.Mask" "F.Paste")
			(net "P12V_AUX")
		)
		(pad "2" smd circle
			(at 0.40005 0 270)
			(size 0 0)
			(layers "F.Cu" "F.Mask" "F.Paste")
			(net "P12V_SCM_VCC")
		)
	)
	(footprint ""
		(layer "F.Cu")
		(at 441.430156 -397.435578 -90)
		(property "Reference" "PC6550_09P0_1"
			(at 0 0 270)
			(layer "F.SilkS")
			(hide yes)
			(effects
				(font
					(size 1.27 1.27)
				)
			)
		)
		(property "Value" ""
			(at 0 0 270)
			(layer "F.Fab")
			(effects
				(font
					(size 1.27 1.27)
				)
			)
		)
		(duplicate_pad_numbers_are_jumpers no)
		(fp_line
			(start -0.7874 0.4064)
			(end -0.7874 -0.4064)
			(stroke
				(width 0.1524)
				(type default)
			)
			(layer "F.SilkS")
		)
		(fp_line
			(start 0.7874 0.4064)
			(end -0.7874 0.4064)
			(stroke
				(width 0.1524)
				(type default)
			)
			(layer "F.SilkS")
		)
		(fp_line
			(start -0.7874 -0.4064)
			(end 0.7874 -0.4064)
			(stroke
				(width 0.1524)
				(type default)
			)
			(layer "F.SilkS")
		)
		(fp_line
			(start 0.7874 -0.4064)
			(end 0.7874 0.4064)
			(stroke
				(width 0.1524)
				(type default)
			)
			(layer "F.SilkS")
		)
		(fp_line
			(start -0.67945 0.3048)
			(end -0.67945 -0.305054)
			(stroke
				(width 0.1)
				(type default)
			)
			(layer "F.Fab")
		)
		(fp_line
			(start -0.12065 0.3048)
			(end -0.67945 0.3048)
			(stroke
				(width 0.1)
				(type default)
			)
			(layer "F.Fab")
		)
		(fp_line
			(start 0.120396 0.3048)
			(end 0.120396 0.2794)
			(stroke
				(width 0.1)
				(type default)
			)
			(layer "F.Fab")
		)
		(fp_line
			(start 0.67945 0.3048)
			(end 0.120396 0.3048)
			(stroke
				(width 0.1)
				(type default)
			)
			(layer "F.Fab")
		)
		(fp_line
			(start -0.12065 0.2794)
			(end -0.12065 0.3048)
			(stroke
				(width 0.1)
				(type default)
			)
			(layer "F.Fab")
		)
		(fp_line
			(start 0.120396 0.2794)
			(end -0.12065 0.2794)
			(stroke
				(width 0.1)
				(type default)
			)
			(layer "F.Fab")
		)
		(fp_line
			(start -0.12065 -0.2794)
			(end 0.12065 -0.2794)
			(stroke
				(width 0.1)
				(type default)
			)
			(layer "F.Fab")
		)
		(fp_line
			(start 0.12065 -0.2794)
			(end 0.12065 -0.3048)
			(stroke
				(width 0.1)
				(type default)
			)
			(layer "F.Fab")
		)
		(fp_line
			(start 0.12065 -0.3048)
			(end 0.67945 -0.3048)
			(stroke
				(width 0.1)
				(type default)
			)
			(layer "F.Fab")
		)
		(fp_line
			(start 0.67945 -0.3048)
			(end 0.67945 0.3048)
			(stroke
				(width 0.1)
				(type default)
			)
			(layer "F.Fab")
		)
		(fp_line
			(start -0.67945 -0.305054)
			(end -0.12065 -0.305054)
			(stroke
				(width 0.1)
				(type default)
			)
			(layer "F.Fab")
		)
		(fp_line
			(start -0.12065 -0.305054)
			(end -0.12065 -0.2794)
			(stroke
				(width 0.1)
				(type default)
			)
			(layer "F.Fab")
		)
		(pad "1" smd circle
			(at -0.40005 0 270)
			(size 0 0)
			(layers "F.Cu" "F.Mask" "F.Paste")
			(net "P0V9_RETIMER_CPU0_PVCC")
		)
		(pad "2" smd circle
			(at 0.40005 0 270)
			(size 0 0)
			(layers "F.Cu" "F.Mask" "F.Paste")
			(net "GND")
		)
	)
	(footprint ""
		(layer "F.Cu")
		(at 118.718584 -59.884056 180)
		(property "Reference" "R1734"
			(at 0 0 180)
			(layer "F.SilkS")
			(hide yes)
			(effects
				(font
					(size 1.27 1.27)
				)
			)
		)
		(property "Value" ""
			(at 0 0 180)
			(layer "F.Fab")
			(effects
				(font
					(size 1.27 1.27)
				)
			)
		)
		(duplicate_pad_numbers_are_jumpers no)
		(fp_line
			(start 0.7874 0.4064)
			(end -0.7874 0.4064)
			(stroke
				(width 0.1524)
				(type default)
			)
			(layer "F.SilkS")
		)
		(fp_line
			(start 0.7874 -0.4064)
			(end 0.7874 0.4064)
			(stroke
				(width 0.1524)
				(type default)
			)
			(layer "F.SilkS")
		)
		(fp_line
			(start -0.7874 0.4064)
			(end -0.7874 -0.4064)
			(stroke
				(width 0.1524)
				(type default)
			)
			(layer "F.SilkS")
		)
		(fp_line
			(start -0.7874 -0.4064)
			(end 0.7874 -0.4064)
			(stroke
				(width 0.1524)
				(type default)
			)
			(layer "F.SilkS")
		)
		(fp_line
			(start 0.67945 0.3048)
			(end 0.120396 0.3048)
			(stroke
				(width 0.1)
				(type default)
			)
			(layer "F.Fab")
		)
		(fp_line
			(start 0.67945 -0.3048)
			(end 0.67945 0.3048)
			(stroke
				(width 0.1)
				(type default)
			)
			(layer "F.Fab")
		)
		(fp_line
			(start 0.12065 -0.2794)
			(end 0.12065 -0.3048)
			(stroke
				(width 0.1)
				(type default)
			)
			(layer "F.Fab")
		)
		(fp_line
			(start 0.12065 -0.3048)
			(end 0.67945 -0.3048)
			(stroke
				(width 0.1)
				(type default)
			)
			(layer "F.Fab")
		)
		(fp_line
			(start 0.120396 0.3048)
			(end 0.120396 0.2794)
			(stroke
				(width 0.1)
				(type default)
			)
			(layer "F.Fab")
		)
		(fp_line
			(start 0.120396 0.2794)
			(end -0.12065 0.2794)
			(stroke
				(width 0.1)
				(type default)
			)
			(layer "F.Fab")
		)
		(fp_line
			(start -0.12065 0.3048)
			(end -0.67945 0.3048)
			(stroke
				(width 0.1)
				(type default)
			)
			(layer "F.Fab")
		)
		(fp_line
			(start -0.12065 0.2794)
			(end -0.12065 0.3048)
			(stroke
				(width 0.1)
				(type default)
			)
			(layer "F.Fab")
		)
		(fp_line
			(start -0.12065 -0.2794)
			(end 0.12065 -0.2794)
			(stroke
				(width 0.1)
				(type default)
			)
			(layer "F.Fab")
		)
		(fp_line
			(start -0.12065 -0.305054)
			(end -0.12065 -0.2794)
			(stroke
				(width 0.1)
				(type default)
			)
			(layer "F.Fab")
		)
		(fp_line
			(start -0.67945 0.3048)
			(end -0.67945 -0.305054)
			(stroke
				(width 0.1)
				(type default)
			)
			(layer "F.Fab")
		)
		(fp_line
			(start -0.67945 -0.305054)
			(end -0.12065 -0.305054)
			(stroke
				(width 0.1)
				(type default)
			)
			(layer "F.Fab")
		)
		(pad "1" smd circle
			(at -0.40005 0 180)
			(size 0 0)
			(layers "F.Cu" "F.Mask" "F.Paste")
			(net "P3V3_AUX")
		)
		(pad "2" smd circle
			(at 0.40005 0 180)
			(size 0 0)
			(layers "F.Cu" "F.Mask" "F.Paste")
			(net "JTAG_SCM_TCK")
		)
	)
	(footprint ""
		(layer "F.Cu")
		(at 144.4752 -75.557126 180)
		(property "Reference" "PC384"
			(at 0 0 180)
			(layer "F.SilkS")
			(hide yes)
			(effects
				(font
					(size 1.27 1.27)
				)
			)
		)
		(property "Value" ""
			(at 0 0 180)
			(layer "F.Fab")
			(effects
				(font
					(size 1.27 1.27)
				)
			)
		)
		(duplicate_pad_numbers_are_jumpers no)
		(fp_line
			(start 0.7874 0.4064)
			(end -0.7874 0.4064)
			(stroke
				(width 0.1524)
				(type default)
			)
			(layer "F.SilkS")
		)
		(fp_line
			(start 0.7874 -0.4064)
			(end 0.7874 0.4064)
			(stroke
				(width 0.1524)
				(type default)
			)
			(layer "F.SilkS")
		)
		(fp_line
			(start -0.7874 0.4064)
			(end -0.7874 -0.4064)
			(stroke
				(width 0.1524)
				(type default)
			)
			(layer "F.SilkS")
		)
		(fp_line
			(start -0.7874 -0.4064)
			(end 0.7874 -0.4064)
			(stroke
				(width 0.1524)
				(type default)
			)
			(layer "F.SilkS")
		)
		(fp_line
			(start 0.67945 0.3048)
			(end 0.120396 0.3048)
			(stroke
				(width 0.1)
				(type default)
			)
			(layer "F.Fab")
		)
		(fp_line
			(start 0.67945 -0.3048)
			(end 0.67945 0.3048)
			(stroke
				(width 0.1)
				(type default)
			)
			(layer "F.Fab")
		)
		(fp_line
			(start 0.12065 -0.2794)
			(end 0.12065 -0.3048)
			(stroke
				(width 0.1)
				(type default)
			)
			(layer "F.Fab")
		)
		(fp_line
			(start 0.12065 -0.3048)
			(end 0.67945 -0.3048)
			(stroke
				(width 0.1)
				(type default)
			)
			(layer "F.Fab")
		)
		(fp_line
			(start 0.120396 0.3048)
			(end 0.120396 0.2794)
			(stroke
				(width 0.1)
				(type default)
			)
			(layer "F.Fab")
		)
		(fp_line
			(start 0.120396 0.2794)
			(end -0.12065 0.2794)
			(stroke
				(width 0.1)
				(type default)
			)
			(layer "F.Fab")
		)
		(fp_line
			(start -0.12065 0.3048)
			(end -0.67945 0.3048)
			(stroke
				(width 0.1)
				(type default)
			)
			(layer "F.Fab")
		)
		(fp_line
			(start -0.12065 0.2794)
			(end -0.12065 0.3048)
			(stroke
				(width 0.1)
				(type default)
			)
			(layer "F.Fab")
		)
		(fp_line
			(start -0.12065 -0.2794)
			(end 0.12065 -0.2794)
			(stroke
				(width 0.1)
				(type default)
			)
			(layer "F.Fab")
		)
		(fp_line
			(start -0.12065 -0.305054)
			(end -0.12065 -0.2794)
			(stroke
				(width 0.1)
				(type default)
			)
			(layer "F.Fab")
		)
		(fp_line
			(start -0.67945 0.3048)
			(end -0.67945 -0.305054)
			(stroke
				(width 0.1)
				(type default)
			)
			(layer "F.Fab")
		)
		(fp_line
			(start -0.67945 -0.305054)
			(end -0.12065 -0.305054)
			(stroke
				(width 0.1)
				(type default)
			)
			(layer "F.Fab")
		)
		(pad "1" smd circle
			(at -0.40005 0 180)
			(size 0 0)
			(layers "F.Cu" "F.Mask" "F.Paste")
			(net "P1V8_AUX_REF")
		)
		(pad "2" smd circle
			(at 0.40005 0 180)
			(size 0 0)
			(layers "F.Cu" "F.Mask" "F.Paste")
			(net "GND")
		)
	)
	(footprint ""
		(layer "F.Cu")
		(at 296.385742 -398.78 90)
		(property "Reference" "R998"
			(at 0 0 90)
			(layer "F.SilkS")
			(hide yes)
			(effects
				(font
					(size 1.27 1.27)
				)
			)
		)
		(property "Value" ""
			(at 0 0 90)
			(layer "F.Fab")
			(effects
				(font
					(size 1.27 1.27)
				)
			)
		)
		(duplicate_pad_numbers_are_jumpers no)
		(fp_line
			(start 0.32512 -0.175006)
			(end 0.32512 0.175006)
			(stroke
				(width 0.1)
				(type default)
			)
			(layer "F.Fab")
		)
		(fp_line
			(start -0.32512 -0.175006)
			(end 0.32512 -0.175006)
			(stroke
				(width 0.1)
				(type default)
			)
			(layer "F.Fab")
		)
		(fp_line
			(start 0.32512 0.175006)
			(end -0.32512 0.175006)
			(stroke
				(width 0.1)
				(type default)
			)
			(layer "F.Fab")
		)
		(fp_line
			(start -0.32512 0.175006)
			(end -0.32512 -0.175006)
			(stroke
				(width 0.1)
				(type default)
			)
			(layer "F.Fab")
		)
		(pad "1" smd rect
			(at -0.2667 0 90)
			(size 0.3048 0.381)
			(layers "F.Cu" "F.Mask" "F.Paste")
			(net "P1V8_CPU0_RT_1D")
		)
		(pad "2" smd rect
			(at 0.2667 0 270)
			(size 0.3048 0.381)
			(layers "F.Cu" "F.Mask" "F.Paste")
			(net "MODE_RT_CPU0_P0")
		)
	)
	(footprint ""
		(layer "F.Cu")
		(at 178.69408 -92.685616 90)
		(property "Reference" "R6742"
			(at 0 0 90)
			(layer "F.SilkS")
			(hide yes)
			(effects
				(font
					(size 1.27 1.27)
				)
			)
		)
		(property "Value" ""
			(at 0 0 90)
			(layer "F.Fab")
			(effects
				(font
					(size 1.27 1.27)
				)
			)
		)
		(duplicate_pad_numbers_are_jumpers no)
		(fp_line
			(start 0.7874 -0.4064)
			(end 0.7874 0.4064)
			(stroke
				(width 0.1524)
				(type default)
			)
			(layer "F.SilkS")
		)
		(fp_line
			(start -0.7874 -0.4064)
			(end 0.7874 -0.4064)
			(stroke
				(width 0.1524)
				(type default)
			)
			(layer "F.SilkS")
		)
		(fp_line
			(start 0.7874 0.4064)
			(end -0.7874 0.4064)
			(stroke
				(width 0.1524)
				(type default)
			)
			(layer "F.SilkS")
		)
		(fp_line
			(start -0.7874 0.4064)
			(end -0.7874 -0.4064)
			(stroke
				(width 0.1524)
				(type default)
			)
			(layer "F.SilkS")
		)
		(fp_line
			(start -0.12065 -0.305054)
			(end -0.12065 -0.2794)
			(stroke
				(width 0.1)
				(type default)
			)
			(layer "F.Fab")
		)
		(fp_line
			(start -0.67945 -0.305054)
			(end -0.12065 -0.305054)
			(stroke
				(width 0.1)
				(type default)
			)
			(layer "F.Fab")
		)
		(fp_line
			(start 0.67945 -0.3048)
			(end 0.67945 0.3048)
			(stroke
				(width 0.1)
				(type default)
			)
			(layer "F.Fab")
		)
		(fp_line
			(start 0.12065 -0.3048)
			(end 0.67945 -0.3048)
			(stroke
				(width 0.1)
				(type default)
			)
			(layer "F.Fab")
		)
		(fp_line
			(start 0.12065 -0.2794)
			(end 0.12065 -0.3048)
			(stroke
				(width 0.1)
				(type default)
			)
			(layer "F.Fab")
		)
		(fp_line
			(start -0.12065 -0.2794)
			(end 0.12065 -0.2794)
			(stroke
				(width 0.1)
				(type default)
			)
			(layer "F.Fab")
		)
		(fp_line
			(start 0.120396 0.2794)
			(end -0.12065 0.2794)
			(stroke
				(width 0.1)
				(type default)
			)
			(layer "F.Fab")
		)
		(fp_line
			(start -0.12065 0.2794)
			(end -0.12065 0.3048)
			(stroke
				(width 0.1)
				(type default)
			)
			(layer "F.Fab")
		)
		(fp_line
			(start 0.67945 0.3048)
			(end 0.120396 0.3048)
			(stroke
				(width 0.1)
				(type default)
			)
			(layer "F.Fab")
		)
		(fp_line
			(start 0.120396 0.3048)
			(end 0.120396 0.2794)
			(stroke
				(width 0.1)
				(type default)
			)
			(layer "F.Fab")
		)
		(fp_line
			(start -0.12065 0.3048)
			(end -0.67945 0.3048)
			(stroke
				(width 0.1)
				(type default)
			)
			(layer "F.Fab")
		)
		(fp_line
			(start -0.67945 0.3048)
			(end -0.67945 -0.305054)
			(stroke
				(width 0.1)
				(type default)
			)
			(layer "F.Fab")
		)
		(pad "1" smd circle
			(at -0.40005 0 90)
			(size 0 0)
			(layers "F.Cu" "F.Mask" "F.Paste")
			(net "P1V8_AUX")
		)
		(pad "2" smd circle
			(at 0.40005 0 90)
			(size 0 0)
			(layers "F.Cu" "F.Mask" "F.Paste")
			(net "RT_BOARD_ID_ID1")
		)
	)
)
